(kicad_pcb
	(version 20260206)
	(generator "pcbnew")
	(generator_version "10.0")
	(general
		(thickness 1.6)
		(legacy_teardrops no)
	)
	(paper "A4")
	(title_block
		(title "03242023_DA0F0TMBIJ0_F0T_Motherboard_J_brd_V01_OCP.brd")
		(comment 1 "Grand Teton / footprints 1342-1347 of 6105")
	)
	(layers
		(0 "F.Cu" signal "TOP")
		(4 "In1.Cu" signal "GND")
		(6 "In2.Cu" signal "IN1")
		(8 "In3.Cu" signal "GND1")
		(10 "In4.Cu" signal "IN2")
		(12 "In5.Cu" signal "GND2")
		(14 "In6.Cu" signal "IN3")
		(16 "In7.Cu" signal "GND3")
		(18 "In8.Cu" signal "VCC")
		(20 "In9.Cu" signal "VCC1")
		(22 "In10.Cu" signal "GND4")
		(24 "In11.Cu" signal "IN4")
		(26 "In12.Cu" signal "GND5")
		(28 "In13.Cu" signal "IN5")
		(30 "In14.Cu" signal "GND6")
		(32 "In15.Cu" signal "IN6")
		(34 "In16.Cu" signal "GND7")
		(2 "B.Cu" signal "BOTTOM")
		(9 "F.Adhes" user "F.Adhesive")
		(11 "B.Adhes" user "B.Adhesive")
		(13 "F.Paste" user "Package Geometry/Pastemask Top")
		(15 "B.Paste" user "Package Geometry/Pastemask Bottom")
		(5 "F.SilkS" user "Ref Des/Silkscreen Top")
		(7 "B.SilkS" user "Ref Des/Silkscreen Bottom")
		(1 "F.Mask" user "Board Geometry/Soldermask Top")
		(3 "B.Mask" user "Board Geometry/Soldermask Bottom")
		(17 "Dwgs.User" user "User.Drawings")
		(19 "Cmts.User" user "User.Comments")
		(21 "Eco1.User" user "User.Eco1")
		(23 "Eco2.User" user "User.Eco2")
		(25 "Edge.Cuts" user "Board Geometry/Outline")
		(27 "Margin" user)
		(31 "F.CrtYd" user "Package Geometry/Place Bound Top")
		(29 "B.CrtYd" user "Package Geometry/Place Bound Bottom")
		(35 "F.Fab" user "Ref Des/Assembly Top")
		(33 "B.Fab" user "Ref Des/Assembly Bottom")
	)
	(footprint ""
		(layer "F.Cu")
		(at 148.13788 -58.638948 180)
		(property "Reference" "C1323"
			(at 0 0 180)
			(layer "F.SilkS")
			(hide yes)
			(effects
				(font
					(size 1.27 1.27)
				)
			)
		)
		(property "Value" ""
			(at 0 0 180)
			(layer "F.Fab")
			(effects
				(font
					(size 1.27 1.27)
				)
			)
		)
		(duplicate_pad_numbers_are_jumpers no)
		(fp_line
			(start 0.7874 0.4064)
			(end -0.7874 0.4064)
			(stroke
				(width 0.1524)
				(type default)
			)
			(layer "F.SilkS")
		)
		(fp_line
			(start 0.7874 -0.4064)
			(end 0.7874 0.4064)
			(stroke
				(width 0.1524)
				(type default)
			)
			(layer "F.SilkS")
		)
		(fp_line
			(start -0.7874 0.4064)
			(end -0.7874 -0.4064)
			(stroke
				(width 0.1524)
				(type default)
			)
			(layer "F.SilkS")
		)
		(fp_line
			(start -0.7874 -0.4064)
			(end 0.7874 -0.4064)
			(stroke
				(width 0.1524)
				(type default)
			)
			(layer "F.SilkS")
		)
		(fp_line
			(start 0.67945 0.3048)
			(end 0.120396 0.3048)
			(stroke
				(width 0.1)
				(type default)
			)
			(layer "F.Fab")
		)
		(fp_line
			(start 0.67945 -0.3048)
			(end 0.67945 0.3048)
			(stroke
				(width 0.1)
				(type default)
			)
			(layer "F.Fab")
		)
		(fp_line
			(start 0.12065 -0.2794)
			(end 0.12065 -0.3048)
			(stroke
				(width 0.1)
				(type default)
			)
			(layer "F.Fab")
		)
		(fp_line
			(start 0.12065 -0.3048)
			(end 0.67945 -0.3048)
			(stroke
				(width 0.1)
				(type default)
			)
			(layer "F.Fab")
		)
		(fp_line
			(start 0.120396 0.3048)
			(end 0.120396 0.2794)
			(stroke
				(width 0.1)
				(type default)
			)
			(layer "F.Fab")
		)
		(fp_line
			(start 0.120396 0.2794)
			(end -0.12065 0.2794)
			(stroke
				(width 0.1)
				(type default)
			)
			(layer "F.Fab")
		)
		(fp_line
			(start -0.12065 0.3048)
			(end -0.67945 0.3048)
			(stroke
				(width 0.1)
				(type default)
			)
			(layer "F.Fab")
		)
		(fp_line
			(start -0.12065 0.2794)
			(end -0.12065 0.3048)
			(stroke
				(width 0.1)
				(type default)
			)
			(layer "F.Fab")
		)
		(fp_line
			(start -0.12065 -0.2794)
			(end 0.12065 -0.2794)
			(stroke
				(width 0.1)
				(type default)
			)
			(layer "F.Fab")
		)
		(fp_line
			(start -0.12065 -0.305054)
			(end -0.12065 -0.2794)
			(stroke
				(width 0.1)
				(type default)
			)
			(layer "F.Fab")
		)
		(fp_line
			(start -0.67945 0.3048)
			(end -0.67945 -0.305054)
			(stroke
				(width 0.1)
				(type default)
			)
			(layer "F.Fab")
		)
		(fp_line
			(start -0.67945 -0.305054)
			(end -0.12065 -0.305054)
			(stroke
				(width 0.1)
				(type default)
			)
			(layer "F.Fab")
		)
		(pad "1" smd circle
			(at -0.40005 0 180)
			(size 0 0)
			(layers "F.Cu" "F.Mask" "F.Paste")
			(net "P1V8_PCH_AUX")
		)
		(pad "2" smd circle
			(at 0.40005 0 180)
			(size 0 0)
			(layers "F.Cu" "F.Mask" "F.Paste")
			(net "GND")
		)
	)
	(footprint ""
		(layer "F.Cu")
		(at 362.646468 -361.72775)
		(property "Reference" "PC337"
			(at 0 0 0)
			(layer "F.SilkS")
			(hide yes)
			(effects
				(font
					(size 1.27 1.27)
				)
			)
		)
		(property "Value" ""
			(at 0 0 0)
			(layer "F.Fab")
			(effects
				(font
					(size 1.27 1.27)
				)
			)
		)
		(duplicate_pad_numbers_are_jumpers no)
		(fp_line
			(start -0.7874 -0.4064)
			(end 0.7874 -0.4064)
			(stroke
				(width 0.1524)
				(type default)
			)
			(layer "F.SilkS")
		)
		(fp_line
			(start -0.7874 0.4064)
			(end -0.7874 -0.4064)
			(stroke
				(width 0.1524)
				(type default)
			)
			(layer "F.SilkS")
		)
		(fp_line
			(start 0.7874 -0.4064)
			(end 0.7874 0.4064)
			(stroke
				(width 0.1524)
				(type default)
			)
			(layer "F.SilkS")
		)
		(fp_line
			(start 0.7874 0.4064)
			(end -0.7874 0.4064)
			(stroke
				(width 0.1524)
				(type default)
			)
			(layer "F.SilkS")
		)
		(fp_line
			(start -0.67945 -0.305054)
			(end -0.12065 -0.305054)
			(stroke
				(width 0.1)
				(type default)
			)
			(layer "F.Fab")
		)
		(fp_line
			(start -0.67945 0.3048)
			(end -0.67945 -0.305054)
			(stroke
				(width 0.1)
				(type default)
			)
			(layer "F.Fab")
		)
		(fp_line
			(start -0.12065 -0.305054)
			(end -0.12065 -0.2794)
			(stroke
				(width 0.1)
				(type default)
			)
			(layer "F.Fab")
		)
		(fp_line
			(start -0.12065 -0.2794)
			(end 0.12065 -0.2794)
			(stroke
				(width 0.1)
				(type default)
			)
			(layer "F.Fab")
		)
		(fp_line
			(start -0.12065 0.2794)
			(end -0.12065 0.3048)
			(stroke
				(width 0.1)
				(type default)
			)
			(layer "F.Fab")
		)
		(fp_line
			(start -0.12065 0.3048)
			(end -0.67945 0.3048)
			(stroke
				(width 0.1)
				(type default)
			)
			(layer "F.Fab")
		)
		(fp_line
			(start 0.120396 0.2794)
			(end -0.12065 0.2794)
			(stroke
				(width 0.1)
				(type default)
			)
			(layer "F.Fab")
		)
		(fp_line
			(start 0.120396 0.3048)
			(end 0.120396 0.2794)
			(stroke
				(width 0.1)
				(type default)
			)
			(layer "F.Fab")
		)
		(fp_line
			(start 0.12065 -0.3048)
			(end 0.67945 -0.3048)
			(stroke
				(width 0.1)
				(type default)
			)
			(layer "F.Fab")
		)
		(fp_line
			(start 0.12065 -0.2794)
			(end 0.12065 -0.3048)
			(stroke
				(width 0.1)
				(type default)
			)
			(layer "F.Fab")
		)
		(fp_line
			(start 0.67945 -0.3048)
			(end 0.67945 0.3048)
			(stroke
				(width 0.1)
				(type default)
			)
			(layer "F.Fab")
		)
		(fp_line
			(start 0.67945 0.3048)
			(end 0.120396 0.3048)
			(stroke
				(width 0.1)
				(type default)
			)
			(layer "F.Fab")
		)
		(pad "1" smd circle
			(at -0.40005 0)
			(size 0 0)
			(layers "F.Cu" "F.Mask" "F.Paste")
			(net "PVCCIN_CPU0_VCC")
		)
		(pad "2" smd circle
			(at 0.40005 0)
			(size 0 0)
			(layers "F.Cu" "F.Mask" "F.Paste")
			(net "GND")
		)
	)
	(footprint ""
		(layer "F.Cu")
		(at 61.121798 -402.371052 -90)
		(property "Reference" "C719"
			(at 0 0 270)
			(layer "F.SilkS")
			(hide yes)
			(effects
				(font
					(size 1.27 1.27)
				)
			)
		)
		(property "Value" ""
			(at 0 0 270)
			(layer "F.Fab")
			(effects
				(font
					(size 1.27 1.27)
				)
			)
		)
		(duplicate_pad_numbers_are_jumpers no)
		(fp_line
			(start -0.299974 0.150114)
			(end -0.299974 -0.150114)
			(stroke
				(width 0.1)
				(type default)
			)
			(layer "F.Fab")
		)
		(fp_line
			(start 0.299974 0.150114)
			(end -0.299974 0.150114)
			(stroke
				(width 0.1)
				(type default)
			)
			(layer "F.Fab")
		)
		(fp_line
			(start -0.299974 -0.150114)
			(end 0.299974 -0.150114)
			(stroke
				(width 0.1)
				(type default)
			)
			(layer "F.Fab")
		)
		(fp_line
			(start 0.299974 -0.150114)
			(end 0.299974 0.150114)
			(stroke
				(width 0.1)
				(type default)
			)
			(layer "F.Fab")
		)
		(pad "1" smd rect
			(at -0.2667 0 270)
			(size 0.3048 0.381)
			(layers "F.Cu" "F.Mask" "F.Paste")
			(net "P5E_CPU1_PE0_TX_C_DP<11>")
		)
		(pad "2" smd rect
			(at 0.2667 0 270)
			(size 0.3048 0.381)
			(layers "F.Cu" "F.Mask" "F.Paste")
			(net "P5E_CPU1_PE0_TX_DP<11>")
		)
	)
	(footprint ""
		(layer "F.Cu")
		(at 171.50588 -130.266948 90)
		(property "Reference" "R991"
			(at 0 0 90)
			(layer "F.SilkS")
			(hide yes)
			(effects
				(font
					(size 1.27 1.27)
				)
			)
		)
		(property "Value" ""
			(at 0 0 90)
			(layer "F.Fab")
			(effects
				(font
					(size 1.27 1.27)
				)
			)
		)
		(duplicate_pad_numbers_are_jumpers no)
		(fp_line
			(start 0.7874 -0.4064)
			(end 0.7874 0.4064)
			(stroke
				(width 0.1524)
				(type default)
			)
			(layer "F.SilkS")
		)
		(fp_line
			(start -0.7874 -0.4064)
			(end 0.7874 -0.4064)
			(stroke
				(width 0.1524)
				(type default)
			)
			(layer "F.SilkS")
		)
		(fp_line
			(start 0.7874 0.4064)
			(end -0.7874 0.4064)
			(stroke
				(width 0.1524)
				(type default)
			)
			(layer "F.SilkS")
		)
		(fp_line
			(start -0.7874 0.4064)
			(end -0.7874 -0.4064)
			(stroke
				(width 0.1524)
				(type default)
			)
			(layer "F.SilkS")
		)
		(fp_line
			(start -0.12065 -0.305054)
			(end -0.12065 -0.2794)
			(stroke
				(width 0.1)
				(type default)
			)
			(layer "F.Fab")
		)
		(fp_line
			(start -0.67945 -0.305054)
			(end -0.12065 -0.305054)
			(stroke
				(width 0.1)
				(type default)
			)
			(layer "F.Fab")
		)
		(fp_line
			(start 0.67945 -0.3048)
			(end 0.67945 0.3048)
			(stroke
				(width 0.1)
				(type default)
			)
			(layer "F.Fab")
		)
		(fp_line
			(start 0.12065 -0.3048)
			(end 0.67945 -0.3048)
			(stroke
				(width 0.1)
				(type default)
			)
			(layer "F.Fab")
		)
		(fp_line
			(start 0.12065 -0.2794)
			(end 0.12065 -0.3048)
			(stroke
				(width 0.1)
				(type default)
			)
			(layer "F.Fab")
		)
		(fp_line
			(start -0.12065 -0.2794)
			(end 0.12065 -0.2794)
			(stroke
				(width 0.1)
				(type default)
			)
			(layer "F.Fab")
		)
		(fp_line
			(start 0.120396 0.2794)
			(end -0.12065 0.2794)
			(stroke
				(width 0.1)
				(type default)
			)
			(layer "F.Fab")
		)
		(fp_line
			(start -0.12065 0.2794)
			(end -0.12065 0.3048)
			(stroke
				(width 0.1)
				(type default)
			)
			(layer "F.Fab")
		)
		(fp_line
			(start 0.67945 0.3048)
			(end 0.120396 0.3048)
			(stroke
				(width 0.1)
				(type default)
			)
			(layer "F.Fab")
		)
		(fp_line
			(start 0.120396 0.3048)
			(end 0.120396 0.2794)
			(stroke
				(width 0.1)
				(type default)
			)
			(layer "F.Fab")
		)
		(fp_line
			(start -0.12065 0.3048)
			(end -0.67945 0.3048)
			(stroke
				(width 0.1)
				(type default)
			)
			(layer "F.Fab")
		)
		(fp_line
			(start -0.67945 0.3048)
			(end -0.67945 -0.305054)
			(stroke
				(width 0.1)
				(type default)
			)
			(layer "F.Fab")
		)
		(pad "1" smd circle
			(at -0.40005 0 90)
			(size 0 0)
			(layers "F.Cu" "F.Mask" "F.Paste")
			(net "FM_AUX_SW_EN")
		)
		(pad "2" smd circle
			(at 0.40005 0 90)
			(size 0 0)
			(layers "F.Cu" "F.Mask" "F.Paste")
			(net "GND")
		)
	)
	(footprint ""
		(layer "F.Cu")
		(at 128.401572 -137.114026)
		(property "Reference" "R537"
			(at 0 0 0)
			(layer "F.SilkS")
			(hide yes)
			(effects
				(font
					(size 1.27 1.27)
				)
			)
		)
		(property "Value" ""
			(at 0 0 0)
			(layer "F.Fab")
			(effects
				(font
					(size 1.27 1.27)
				)
			)
		)
		(duplicate_pad_numbers_are_jumpers no)
		(fp_line
			(start -0.7874 -0.4064)
			(end 0.7874 -0.4064)
			(stroke
				(width 0.1524)
				(type default)
			)
			(layer "F.SilkS")
		)
		(fp_line
			(start -0.7874 0.4064)
			(end -0.7874 -0.4064)
			(stroke
				(width 0.1524)
				(type default)
			)
			(layer "F.SilkS")
		)
		(fp_line
			(start 0.7874 -0.4064)
			(end 0.7874 0.4064)
			(stroke
				(width 0.1524)
				(type default)
			)
			(layer "F.SilkS")
		)
		(fp_line
			(start 0.7874 0.4064)
			(end -0.7874 0.4064)
			(stroke
				(width 0.1524)
				(type default)
			)
			(layer "F.SilkS")
		)
		(fp_line
			(start -0.67945 -0.305054)
			(end -0.12065 -0.305054)
			(stroke
				(width 0.1)
				(type default)
			)
			(layer "F.Fab")
		)
		(fp_line
			(start -0.67945 0.3048)
			(end -0.67945 -0.305054)
			(stroke
				(width 0.1)
				(type default)
			)
			(layer "F.Fab")
		)
		(fp_line
			(start -0.12065 -0.305054)
			(end -0.12065 -0.2794)
			(stroke
				(width 0.1)
				(type default)
			)
			(layer "F.Fab")
		)
		(fp_line
			(start -0.12065 -0.2794)
			(end 0.12065 -0.2794)
			(stroke
				(width 0.1)
				(type default)
			)
			(layer "F.Fab")
		)
		(fp_line
			(start -0.12065 0.2794)
			(end -0.12065 0.3048)
			(stroke
				(width 0.1)
				(type default)
			)
			(layer "F.Fab")
		)
		(fp_line
			(start -0.12065 0.3048)
			(end -0.67945 0.3048)
			(stroke
				(width 0.1)
				(type default)
			)
			(layer "F.Fab")
		)
		(fp_line
			(start 0.120396 0.2794)
			(end -0.12065 0.2794)
			(stroke
				(width 0.1)
				(type default)
			)
			(layer "F.Fab")
		)
		(fp_line
			(start 0.120396 0.3048)
			(end 0.120396 0.2794)
			(stroke
				(width 0.1)
				(type default)
			)
			(layer "F.Fab")
		)
		(fp_line
			(start 0.12065 -0.3048)
			(end 0.67945 -0.3048)
			(stroke
				(width 0.1)
				(type default)
			)
			(layer "F.Fab")
		)
		(fp_line
			(start 0.12065 -0.2794)
			(end 0.12065 -0.3048)
			(stroke
				(width 0.1)
				(type default)
			)
			(layer "F.Fab")
		)
		(fp_line
			(start 0.67945 -0.3048)
			(end 0.67945 0.3048)
			(stroke
				(width 0.1)
				(type default)
			)
			(layer "F.Fab")
		)
		(fp_line
			(start 0.67945 0.3048)
			(end 0.120396 0.3048)
			(stroke
				(width 0.1)
				(type default)
			)
			(layer "F.Fab")
		)
		(pad "1" smd circle
			(at -0.40005 0)
			(size 0 0)
			(layers "F.Cu" "F.Mask" "F.Paste")
			(net "PCA9548_PCIE3_ADDR2")
		)
		(pad "2" smd circle
			(at 0.40005 0)
			(size 0 0)
			(layers "F.Cu" "F.Mask" "F.Paste")
			(net "GND")
		)
	)
	(footprint ""
		(layer "F.Cu")
		(at 329.240388 -4.696206 180)
		(property "Reference" "J81"
			(at -4.415282 -1.140206 90)
			(unlocked yes)
			(layer "F.SilkS")
			(effects
				(font
					(size 0.7874 0.5842)
					(thickness 0.1524)
				)
				(justify left)
			)
		)
		(property "Value" ""
			(at 0 0 180)
			(layer "F.Fab")
			(effects
				(font
					(size 1.27 1.27)
				)
			)
		)
		(duplicate_pad_numbers_are_jumpers no)
		(fp_line
			(start 1.2192 2.1082)
			(end -1.2192 2.1082)
			(stroke
				(width 0.1524)
				(type default)
			)
			(layer "F.SilkS")
		)
		(fp_line
			(start 1.2192 -2.1082)
			(end 1.2192 2.1082)
			(stroke
				(width 0.1524)
				(type default)
			)
			(layer "F.SilkS")
		)
		(fp_line
			(start -1.2192 2.1082)
			(end -1.2192 -2.1082)
			(stroke
				(width 0.1524)
				(type default)
			)
			(layer "F.SilkS")
		)
		(fp_line
			(start -1.2192 -2.1082)
			(end 1.2192 -2.1082)
			(stroke
				(width 0.1524)
				(type default)
			)
			(layer "F.SilkS")
		)
		(pad "" np_thru_hole circle
			(at -2.8829 -1.27 90)
			(size 1.0414 1.0414)
			(drill 1.0414)
			(layers "*.Cu" "*.Mask")
			(clearance 0.381)
			(thermal_gap 0.381)
		)
		(pad "" np_thru_hole circle
			(at -2.8829 1.27 90)
			(size 1.0414 1.0414)
			(drill 1.0414)
			(layers "*.Cu" "*.Mask")
			(clearance 0.381)
			(thermal_gap 0.381)
		)
		(pad "" np_thru_hole circle
			(at 3.4671 -1.27 90)
			(size 1.0414 1.0414)
			(drill 1.0414)
			(layers "*.Cu" "*.Mask")
			(clearance 0.381)
			(thermal_gap 0.381)
		)
		(pad "" np_thru_hole circle
			(at 3.4671 1.27 90)
			(size 1.0414 1.0414)
			(drill 1.0414)
			(layers "*.Cu" "*.Mask")
			(clearance 0.381)
			(thermal_gap 0.381)
		)
		(pad "1" smd rect
			(at 0.8255 -0.249936 90)
			(size 0.3048 0.508)
			(layers "F.Cu" "F.Mask" "F.Paste")
			(net "DELTA_L_85_10INCH_TOP_DN")
		)
		(pad "2" smd rect
			(at 0.8255 0.249936 90)
			(size 0.3048 0.508)
			(layers "F.Cu" "F.Mask" "F.Paste")
			(net "DELTA_L_85_10INCH_TOP_DP")
		)
		(pad "3" smd circle
			(at 0 0 180)
			(size 0 0)
			(layers "F.Cu" "F.Mask" "F.Paste")
			(net "DELTA_L_GND_1")
		)
		(zone
			(layer "F.Cu")
			(hatch none 0.5)
			(connect_pads
				(clearance 0)
			)
			(min_thickness 0.25)
			(keepout
				(tracks not_allowed)
				(vias allowed)
				(pads allowed)
				(copperpour not_allowed)
				(footprints allowed)
			)
			(placement
				(enabled no)
				(sheetname "")
			)
			(fill
				(thermal_gap 0.5)
				(thermal_bridge_width 0.5)
				(island_removal_mode 0)
			)
			(polygon
				(pts
					(xy 328.122788 -4.147566) (xy 328.122788 -4.24307) (xy 328.719688 -4.24307) (xy 328.719688 -4.64947)
					(xy 328.122788 -4.64947) (xy 328.122788 -4.742942) (xy 328.719688 -4.742942) (xy 328.719688 -5.149342)
					(xy 328.122788 -5.149342) (xy 328.122788 -5.244846) (xy 328.821288 -5.244846) (xy 328.821288 -4.147566)
				)
			)
		)
		(zone
			(layers "F.Cu" "B.Cu" "In1.Cu" "In2.Cu" "In3.Cu" "In4.Cu" "In5.Cu" "In6.Cu"
				"In7.Cu" "In8.Cu" "In9.Cu" "In10.Cu" "In11.Cu" "In12.Cu" "In13.Cu" "In14.Cu"
				"In15.Cu" "In16.Cu"
			)
			(hatch none 0.5)
			(connect_pads
				(clearance 0)
			)
			(min_thickness 0.25)
			(keepout
				(tracks not_allowed)
				(vias allowed)
				(pads allowed)
				(copperpour not_allowed)
				(footprints allowed)
			)
			(placement
				(enabled no)
				(sheetname "")
			)
			(fill
				(thermal_gap 0.5)
				(thermal_bridge_width 0.5)
				(island_removal_mode 0)
			)
			(polygon
				(pts
					(arc
						(start 326.700388 -5.966206)
						(mid 324.846188 -5.966206)
						(end 326.700388 -5.966206)
					)
				)
			)
		)
		(zone
			(layers "F.Cu" "B.Cu" "In1.Cu" "In2.Cu" "In3.Cu" "In4.Cu" "In5.Cu" "In6.Cu"
				"In7.Cu" "In8.Cu" "In9.Cu" "In10.Cu" "In11.Cu" "In12.Cu" "In13.Cu" "In14.Cu"
				"In15.Cu" "In16.Cu"
			)
			(hatch none 0.5)
			(connect_pads
				(clearance 0)
			)
			(min_thickness 0.25)
			(keepout
				(tracks not_allowed)
				(vias allowed)
				(pads allowed)
				(copperpour not_allowed)
				(footprints allowed)
			)
			(placement
				(enabled no)
				(sheetname "")
			)
			(fill
				(thermal_gap 0.5)
				(thermal_bridge_width 0.5)
				(island_removal_mode 0)
			)
			(polygon
				(pts
					(arc
						(start 326.700388 -3.426206)
						(mid 324.846188 -3.426206)
						(end 326.700388 -3.426206)
					)
				)
			)
		)
		(zone
			(layers "F.Cu" "B.Cu" "In1.Cu" "In2.Cu" "In3.Cu" "In4.Cu" "In5.Cu" "In6.Cu"
				"In7.Cu" "In8.Cu" "In9.Cu" "In10.Cu" "In11.Cu" "In12.Cu" "In13.Cu" "In14.Cu"
				"In15.Cu" "In16.Cu"
			)
			(hatch none 0.5)
			(connect_pads
				(clearance 0)
			)
			(min_thickness 0.25)
			(keepout
				(tracks not_allowed)
				(vias allowed)
				(pads allowed)
				(copperpour not_allowed)
				(footprints allowed)
			)
			(placement
				(enabled no)
				(sheetname "")
			)
			(fill
				(thermal_gap 0.5)
				(thermal_bridge_width 0.5)
				(island_removal_mode 0)
			)
			(polygon
				(pts
					(arc
						(start 333.050388 -5.966206)
						(mid 331.196188 -5.966206)
						(end 333.050388 -5.966206)
					)
				)
			)
		)
		(zone
			(layers "F.Cu" "B.Cu" "In1.Cu" "In2.Cu" "In3.Cu" "In4.Cu" "In5.Cu" "In6.Cu"
				"In7.Cu" "In8.Cu" "In9.Cu" "In10.Cu" "In11.Cu" "In12.Cu" "In13.Cu" "In14.Cu"
				"In15.Cu" "In16.Cu"
			)
			(hatch none 0.5)
			(connect_pads
				(clearance 0)
			)
			(min_thickness 0.25)
			(keepout
				(tracks not_allowed)
				(vias allowed)
				(pads allowed)
				(copperpour not_allowed)
				(footprints allowed)
			)
			(placement
				(enabled no)
				(sheetname "")
			)
			(fill
				(thermal_gap 0.5)
				(thermal_bridge_width 0.5)
				(island_removal_mode 0)
			)
			(polygon
				(pts
					(arc
						(start 333.050388 -3.426206)
						(mid 331.196188 -3.426206)
						(end 333.050388 -3.426206)
					)
				)
			)
		)
	)
)
